# T6G (Grand Teton) — schematic netlist excerpt (pin names and nets, part order shuffled) for the footprints in the layout excerpt that follows; sources: Cadence DE-HDL packaged netlist, KiCad conversion of 04192023_DAF0TMB3IC0_F0TG_MB_C_brd_V02_OCP.brd

R3554  Q_RES  33.2 1% CHIP  pkg 0402LF  page 235 : A = SMB_LM75_3_3V3AUX_SDA ; B = SMB_LM75_3_3V3AUX_SDA_R1
PR513  Q_RES  1.5 1% EMPTY  pkg 0402LF  page 218 : A = SW_PVDDCR_CPU1_P1_SW2_RC ; B = GND

(kicad_pcb
	(version 20260206)
	(generator "pcbnew")
	(generator_version "10.0")
	(general
		(thickness 1.6)
		(legacy_teardrops no)
	)
	(paper "A4")
	(title_block
		(title "04192023_DAF0TMB3IC0_F0TG_MB_C_brd_V02_OCP.brd")
		(comment 1 "Grand Teton / footprints 3779-3780 of 8354")
	)
	(layers
		(0 "F.Cu" signal "TOP")
		(4 "In1.Cu" signal "GND")
		(6 "In2.Cu" signal "IN1")
		(8 "In3.Cu" signal "GND1")
		(10 "In4.Cu" signal "IN2")
		(12 "In5.Cu" signal "GND2")
		(14 "In6.Cu" signal "IN3")
		(16 "In7.Cu" signal "GND3")
		(18 "In8.Cu" signal "VCC")
		(20 "In9.Cu" signal "VCC1")
		(22 "In10.Cu" signal "GND4")
		(24 "In11.Cu" signal "IN4")
		(26 "In12.Cu" signal "GND5")
		(28 "In13.Cu" signal "IN5")
		(30 "In14.Cu" signal "GND6")
		(32 "In15.Cu" signal "IN6")
		(34 "In16.Cu" signal "GND7")
		(2 "B.Cu" signal "BOTTOM")
		(9 "F.Adhes" user "F.Adhesive")
		(11 "B.Adhes" user "B.Adhesive")
		(13 "F.Paste" user "Package Geometry/Pastemask Top")
		(15 "B.Paste" user "Package Geometry/Pastemask Bottom")
		(5 "F.SilkS" user "Ref Des/Silkscreen Top")
		(7 "B.SilkS" user "Ref Des/Silkscreen Bottom")
		(1 "F.Mask" user "Board Geometry/Soldermask Top")
		(3 "B.Mask" user "Board Geometry/Soldermask Bottom")
		(17 "Dwgs.User" user "User.Drawings")
		(19 "Cmts.User" user "User.Comments")
		(21 "Eco1.User" user "User.Eco1")
		(23 "Eco2.User" user "User.Eco2")
		(25 "Edge.Cuts" user "Board Geometry/Outline")
		(27 "Margin" user)
		(31 "F.CrtYd" user "Package Geometry/Place Bound Top")
		(29 "B.CrtYd" user "Package Geometry/Place Bound Bottom")
		(35 "F.Fab" user "Ref Des/Assembly Top")
		(33 "B.Fab" user "Ref Des/Assembly Bottom")
	)
	(footprint ""
		(layer "F.Cu")
		(at 75.08748 -333.258668 90)
		(property "Reference" "PR513"
			(at 0 0 90)
			(layer "F.SilkS")
			(hide yes)
			(effects
				(font
					(size 1.27 1.27)
				)
			)
		)
		(property "Value" ""
			(at 0 0 90)
			(layer "F.Fab")
			(effects
				(font
					(size 1.27 1.27)
				)
			)
		)
		(duplicate_pad_numbers_are_jumpers no)
		(fp_line
			(start 0.7874 -0.4064)
			(end 0.7874 0.4064)
			(stroke
				(width 0.1524)
				(type default)
			)
			(layer "F.SilkS")
		)
		(fp_line
			(start -0.7874 -0.4064)
			(end 0.7874 -0.4064)
			(stroke
				(width 0.1524)
				(type default)
			)
			(layer "F.SilkS")
		)
		(fp_line
			(start 0.7874 0.4064)
			(end -0.7874 0.4064)
			(stroke
				(width 0.1524)
				(type default)
			)
			(layer "F.SilkS")
		)
		(fp_line
			(start -0.7874 0.4064)
			(end -0.7874 -0.4064)
			(stroke
				(width 0.1524)
				(type default)
			)
			(layer "F.SilkS")
		)
		(fp_line
			(start -0.12065 -0.305054)
			(end -0.12065 -0.2794)
			(stroke
				(width 0.1)
				(type default)
			)
			(layer "F.Fab")
		)
		(fp_line
			(start -0.67945 -0.305054)
			(end -0.12065 -0.305054)
			(stroke
				(width 0.1)
				(type default)
			)
			(layer "F.Fab")
		)
		(fp_line
			(start 0.67945 -0.3048)
			(end 0.67945 0.3048)
			(stroke
				(width 0.1)
				(type default)
			)
			(layer "F.Fab")
		)
		(fp_line
			(start 0.12065 -0.3048)
			(end 0.67945 -0.3048)
			(stroke
				(width 0.1)
				(type default)
			)
			(layer "F.Fab")
		)
		(fp_line
			(start 0.12065 -0.2794)
			(end 0.12065 -0.3048)
			(stroke
				(width 0.1)
				(type default)
			)
			(layer "F.Fab")
		)
		(fp_line
			(start -0.12065 -0.2794)
			(end 0.12065 -0.2794)
			(stroke
				(width 0.1)
				(type default)
			)
			(layer "F.Fab")
		)
		(fp_line
			(start 0.120396 0.2794)
			(end -0.12065 0.2794)
			(stroke
				(width 0.1)
				(type default)
			)
			(layer "F.Fab")
		)
		(fp_line
			(start -0.12065 0.2794)
			(end -0.12065 0.3048)
			(stroke
				(width 0.1)
				(type default)
			)
			(layer "F.Fab")
		)
		(fp_line
			(start 0.67945 0.3048)
			(end 0.120396 0.3048)
			(stroke
				(width 0.1)
				(type default)
			)
			(layer "F.Fab")
		)
		(fp_line
			(start 0.120396 0.3048)
			(end 0.120396 0.2794)
			(stroke
				(width 0.1)
				(type default)
			)
			(layer "F.Fab")
		)
		(fp_line
			(start -0.12065 0.3048)
			(end -0.67945 0.3048)
			(stroke
				(width 0.1)
				(type default)
			)
			(layer "F.Fab")
		)
		(fp_line
			(start -0.67945 0.3048)
			(end -0.67945 -0.305054)
			(stroke
				(width 0.1)
				(type default)
			)
			(layer "F.Fab")
		)
		(pad "1" smd circle
			(at -0.40005 0 90)
			(size 0 0)
			(layers "F.Cu" "F.Mask" "F.Paste")
			(net "SW_PVDDCR_CPU1_P1_SW2_RC")
		)
		(pad "2" smd circle
			(at 0.40005 0 90)
			(size 0 0)
			(layers "F.Cu" "F.Mask" "F.Paste")
			(net "GND")
		)
	)
	(footprint ""
		(layer "F.Cu")
		(at 106.892598 -18.20291)
		(property "Reference" "R3554"
			(at 0 0 0)
			(layer "F.SilkS")
			(hide yes)
			(effects
				(font
					(size 1.27 1.27)
				)
			)
		)
		(property "Value" ""
			(at 0 0 0)
			(layer "F.Fab")
			(effects
				(font
					(size 1.27 1.27)
				)
			)
		)
		(duplicate_pad_numbers_are_jumpers no)
		(fp_line
			(start -0.7874 -0.4064)
			(end 0.7874 -0.4064)
			(stroke
				(width 0.1524)
				(type default)
			)
			(layer "F.SilkS")
		)
		(fp_line
			(start -0.7874 0.4064)
			(end -0.7874 -0.4064)
			(stroke
				(width 0.1524)
				(type default)
			)
			(layer "F.SilkS")
		)
		(fp_line
			(start 0.7874 -0.4064)
			(end 0.7874 0.4064)
			(stroke
				(width 0.1524)
				(type default)
			)
			(layer "F.SilkS")
		)
		(fp_line
			(start 0.7874 0.4064)
			(end -0.7874 0.4064)
			(stroke
				(width 0.1524)
				(type default)
			)
			(layer "F.SilkS")
		)
		(fp_line
			(start -0.67945 -0.305054)
			(end -0.12065 -0.305054)
			(stroke
				(width 0.1)
				(type default)
			)
			(layer "F.Fab")
		)
		(fp_line
			(start -0.67945 0.3048)
			(end -0.67945 -0.305054)
			(stroke
				(width 0.1)
				(type default)
			)
			(layer "F.Fab")
		)
		(fp_line
			(start -0.12065 -0.305054)
			(end -0.12065 -0.2794)
			(stroke
				(width 0.1)
				(type default)
			)
			(layer "F.Fab")
		)
		(fp_line
			(start -0.12065 -0.2794)
			(end 0.12065 -0.2794)
			(stroke
				(width 0.1)
				(type default)
			)
			(layer "F.Fab")
		)
		(fp_line
			(start -0.12065 0.2794)
			(end -0.12065 0.3048)
			(stroke
				(width 0.1)
				(type default)
			)
			(layer "F.Fab")
		)
		(fp_line
			(start -0.12065 0.3048)
			(end -0.67945 0.3048)
			(stroke
				(width 0.1)
				(type default)
			)
			(layer "F.Fab")
		)
		(fp_line
			(start 0.120396 0.2794)
			(end -0.12065 0.2794)
			(stroke
				(width 0.1)
				(type default)
			)
			(layer "F.Fab")
		)
		(fp_line
			(start 0.120396 0.3048)
			(end 0.120396 0.2794)
			(stroke
				(width 0.1)
				(type default)
			)
			(layer "F.Fab")
		)
		(fp_line
			(start 0.12065 -0.3048)
			(end 0.67945 -0.3048)
			(stroke
				(width 0.1)
				(type default)
			)
			(layer "F.Fab")
		)
		(fp_line
			(start 0.12065 -0.2794)
			(end 0.12065 -0.3048)
			(stroke
				(width 0.1)
				(type default)
			)
			(layer "F.Fab")
		)
		(fp_line
			(start 0.67945 -0.3048)
			(end 0.67945 0.3048)
			(stroke
				(width 0.1)
				(type default)
			)
			(layer "F.Fab")
		)
		(fp_line
			(start 0.67945 0.3048)
			(end 0.120396 0.3048)
			(stroke
				(width 0.1)
				(type default)
			)
			(layer "F.Fab")
		)
		(pad "1" smd circle
			(at -0.40005 0)
			(size 0 0)
			(layers "F.Cu" "F.Mask" "F.Paste")
			(net "SMB_LM75_3_3V3AUX_SDA")
		)
		(pad "2" smd circle
			(at 0.40005 0)
			(size 0 0)
			(layers "F.Cu" "F.Mask" "F.Paste")
			(net "SMB_LM75_3_3V3AUX_SDA_R1")
		)
	)
)
